(kicad_pcb
	(version 20260206)
	(generator "pcbnew")
	(generator_version "10.0")
	(general
		(thickness 1.6)
		(legacy_teardrops no)
	)
	(paper "A4")
	(title_block
		(title "01162023_DA0F0TEBIF0_F0T_Expander_BD_F_brd_V02_OCP.brd")
		(comment 1 "Grand Teton / footprints 107-113 of 9728")
	)
	(layers
		(0 "F.Cu" signal "TOP")
		(4 "In1.Cu" signal "GND")
		(6 "In2.Cu" signal "VCC")
		(8 "In3.Cu" signal "VCC1")
		(10 "In4.Cu" signal "GND1")
		(12 "In5.Cu" signal "IN1")
		(14 "In6.Cu" signal "GND2")
		(16 "In7.Cu" signal "IN2")
		(18 "In8.Cu" signal "GND3")
		(20 "In9.Cu" signal "IN3")
		(22 "In10.Cu" signal "GND4")
		(24 "In11.Cu" signal "IN4")
		(26 "In12.Cu" signal "GND5")
		(28 "In13.Cu" signal "IN5")
		(30 "In14.Cu" signal "GND6")
		(32 "In15.Cu" signal "IN6")
		(34 "In16.Cu" signal "GND7")
		(2 "B.Cu" signal "BOTTOM")
		(9 "F.Adhes" user "F.Adhesive")
		(11 "B.Adhes" user "B.Adhesive")
		(13 "F.Paste" user "Package Geometry/Pastemask Top")
		(15 "B.Paste" user "Package Geometry/Pastemask Bottom")
		(5 "F.SilkS" user "Ref Des/Silkscreen Top")
		(7 "B.SilkS" user "Ref Des/Silkscreen Bottom")
		(1 "F.Mask" user "Board Geometry/Soldermask Top")
		(3 "B.Mask" user "Board Geometry/Soldermask Bottom")
		(17 "Dwgs.User" user "User.Drawings")
		(19 "Cmts.User" user "User.Comments")
		(21 "Eco1.User" user "User.Eco1")
		(23 "Eco2.User" user "User.Eco2")
		(25 "Edge.Cuts" user "Board Geometry/Outline")
		(27 "Margin" user)
		(31 "F.CrtYd" user "Package Geometry/Place Bound Top")
		(29 "B.CrtYd" user "Package Geometry/Place Bound Bottom")
		(35 "F.Fab" user "Ref Des/Assembly Top")
		(33 "B.Fab" user "Ref Des/Assembly Bottom")
	)
	(footprint ""
		(layer "F.Cu")
		(at 14.252956 -394.13053 -90)
		(property "Reference" "R6746"
			(at 0 0 270)
			(layer "F.SilkS")
			(hide yes)
			(effects
				(font
					(size 1.27 1.27)
				)
			)
		)
		(property "Value" ""
			(at 0 0 270)
			(layer "F.Fab")
			(effects
				(font
					(size 1.27 1.27)
				)
			)
		)
		(duplicate_pad_numbers_are_jumpers no)
		(fp_line
			(start -0.7874 0.4064)
			(end -0.7874 -0.4064)
			(stroke
				(width 0.1524)
				(type default)
			)
			(layer "F.SilkS")
		)
		(fp_line
			(start 0.7874 0.4064)
			(end -0.7874 0.4064)
			(stroke
				(width 0.1524)
				(type default)
			)
			(layer "F.SilkS")
		)
		(fp_line
			(start -0.7874 -0.4064)
			(end 0.7874 -0.4064)
			(stroke
				(width 0.1524)
				(type default)
			)
			(layer "F.SilkS")
		)
		(fp_line
			(start 0.7874 -0.4064)
			(end 0.7874 0.4064)
			(stroke
				(width 0.1524)
				(type default)
			)
			(layer "F.SilkS")
		)
		(fp_line
			(start -0.67945 0.3048)
			(end -0.67945 -0.305054)
			(stroke
				(width 0.1)
				(type default)
			)
			(layer "F.Fab")
		)
		(fp_line
			(start -0.12065 0.3048)
			(end -0.67945 0.3048)
			(stroke
				(width 0.1)
				(type default)
			)
			(layer "F.Fab")
		)
		(fp_line
			(start 0.120396 0.3048)
			(end 0.120396 0.2794)
			(stroke
				(width 0.1)
				(type default)
			)
			(layer "F.Fab")
		)
		(fp_line
			(start 0.67945 0.3048)
			(end 0.120396 0.3048)
			(stroke
				(width 0.1)
				(type default)
			)
			(layer "F.Fab")
		)
		(fp_line
			(start -0.12065 0.2794)
			(end -0.12065 0.3048)
			(stroke
				(width 0.1)
				(type default)
			)
			(layer "F.Fab")
		)
		(fp_line
			(start 0.120396 0.2794)
			(end -0.12065 0.2794)
			(stroke
				(width 0.1)
				(type default)
			)
			(layer "F.Fab")
		)
		(fp_line
			(start -0.12065 -0.2794)
			(end 0.12065 -0.2794)
			(stroke
				(width 0.1)
				(type default)
			)
			(layer "F.Fab")
		)
		(fp_line
			(start 0.12065 -0.2794)
			(end 0.12065 -0.3048)
			(stroke
				(width 0.1)
				(type default)
			)
			(layer "F.Fab")
		)
		(fp_line
			(start 0.12065 -0.3048)
			(end 0.67945 -0.3048)
			(stroke
				(width 0.1)
				(type default)
			)
			(layer "F.Fab")
		)
		(fp_line
			(start 0.67945 -0.3048)
			(end 0.67945 0.3048)
			(stroke
				(width 0.1)
				(type default)
			)
			(layer "F.Fab")
		)
		(fp_line
			(start -0.67945 -0.305054)
			(end -0.12065 -0.305054)
			(stroke
				(width 0.1)
				(type default)
			)
			(layer "F.Fab")
		)
		(fp_line
			(start -0.12065 -0.305054)
			(end -0.12065 -0.2794)
			(stroke
				(width 0.1)
				(type default)
			)
			(layer "F.Fab")
		)
		(pad "1" smd circle
			(at -0.40005 0 270)
			(size 0 0)
			(layers "F.Cu" "F.Mask" "F.Paste")
			(net "GND")
		)
		(pad "2" smd circle
			(at 0.40005 0 270)
			(size 0 0)
			(layers "F.Cu" "F.Mask" "F.Paste")
			(net "BIC_USB_8042_HUB_FULLPWRMGMTZ")
		)
	)
	(footprint ""
		(layer "F.Cu")
		(at 114.23523 -159.27324 -90)
		(property "Reference" "PC42"
			(at 0 0 270)
			(layer "F.SilkS")
			(hide yes)
			(effects
				(font
					(size 1.27 1.27)
				)
			)
		)
		(property "Value" ""
			(at 0 0 270)
			(layer "F.Fab")
			(effects
				(font
					(size 1.27 1.27)
				)
			)
		)
		(duplicate_pad_numbers_are_jumpers no)
		(fp_line
			(start -0.7874 0.4064)
			(end -0.7874 -0.4064)
			(stroke
				(width 0.1524)
				(type default)
			)
			(layer "F.SilkS")
		)
		(fp_line
			(start 0.7874 0.4064)
			(end -0.7874 0.4064)
			(stroke
				(width 0.1524)
				(type default)
			)
			(layer "F.SilkS")
		)
		(fp_line
			(start -0.7874 -0.4064)
			(end 0.7874 -0.4064)
			(stroke
				(width 0.1524)
				(type default)
			)
			(layer "F.SilkS")
		)
		(fp_line
			(start 0.7874 -0.4064)
			(end 0.7874 0.4064)
			(stroke
				(width 0.1524)
				(type default)
			)
			(layer "F.SilkS")
		)
		(fp_line
			(start -0.67945 0.3048)
			(end -0.67945 -0.305054)
			(stroke
				(width 0.1)
				(type default)
			)
			(layer "F.Fab")
		)
		(fp_line
			(start -0.12065 0.3048)
			(end -0.67945 0.3048)
			(stroke
				(width 0.1)
				(type default)
			)
			(layer "F.Fab")
		)
		(fp_line
			(start 0.120396 0.3048)
			(end 0.120396 0.2794)
			(stroke
				(width 0.1)
				(type default)
			)
			(layer "F.Fab")
		)
		(fp_line
			(start 0.67945 0.3048)
			(end 0.120396 0.3048)
			(stroke
				(width 0.1)
				(type default)
			)
			(layer "F.Fab")
		)
		(fp_line
			(start -0.12065 0.2794)
			(end -0.12065 0.3048)
			(stroke
				(width 0.1)
				(type default)
			)
			(layer "F.Fab")
		)
		(fp_line
			(start 0.120396 0.2794)
			(end -0.12065 0.2794)
			(stroke
				(width 0.1)
				(type default)
			)
			(layer "F.Fab")
		)
		(fp_line
			(start -0.12065 -0.2794)
			(end 0.12065 -0.2794)
			(stroke
				(width 0.1)
				(type default)
			)
			(layer "F.Fab")
		)
		(fp_line
			(start 0.12065 -0.2794)
			(end 0.12065 -0.3048)
			(stroke
				(width 0.1)
				(type default)
			)
			(layer "F.Fab")
		)
		(fp_line
			(start 0.12065 -0.3048)
			(end 0.67945 -0.3048)
			(stroke
				(width 0.1)
				(type default)
			)
			(layer "F.Fab")
		)
		(fp_line
			(start 0.67945 -0.3048)
			(end 0.67945 0.3048)
			(stroke
				(width 0.1)
				(type default)
			)
			(layer "F.Fab")
		)
		(fp_line
			(start -0.67945 -0.305054)
			(end -0.12065 -0.305054)
			(stroke
				(width 0.1)
				(type default)
			)
			(layer "F.Fab")
		)
		(fp_line
			(start -0.12065 -0.305054)
			(end -0.12065 -0.2794)
			(stroke
				(width 0.1)
				(type default)
			)
			(layer "F.Fab")
		)
		(pad "1" smd circle
			(at -0.40005 0 270)
			(size 0 0)
			(layers "F.Cu" "F.Mask" "F.Paste")
			(net "P3V3_AUX_REF")
		)
		(pad "2" smd circle
			(at 0.40005 0 270)
			(size 0 0)
			(layers "F.Cu" "F.Mask" "F.Paste")
			(net "GND")
		)
	)
	(footprint ""
		(layer "F.Cu")
		(at 325.197724 -296.365168 90)
		(property "Reference" "C2782"
			(at 0 0 90)
			(layer "F.SilkS")
			(hide yes)
			(effects
				(font
					(size 1.27 1.27)
				)
			)
		)
		(property "Value" ""
			(at 0 0 90)
			(layer "F.Fab")
			(effects
				(font
					(size 1.27 1.27)
				)
			)
		)
		(duplicate_pad_numbers_are_jumpers no)
		(fp_line
			(start 0.7874 -0.4064)
			(end 0.7874 0.4064)
			(stroke
				(width 0.1524)
				(type default)
			)
			(layer "F.SilkS")
		)
		(fp_line
			(start -0.7874 -0.4064)
			(end 0.7874 -0.4064)
			(stroke
				(width 0.1524)
				(type default)
			)
			(layer "F.SilkS")
		)
		(fp_line
			(start 0.7874 0.4064)
			(end -0.7874 0.4064)
			(stroke
				(width 0.1524)
				(type default)
			)
			(layer "F.SilkS")
		)
		(fp_line
			(start -0.7874 0.4064)
			(end -0.7874 -0.4064)
			(stroke
				(width 0.1524)
				(type default)
			)
			(layer "F.SilkS")
		)
		(fp_line
			(start -0.12065 -0.305054)
			(end -0.12065 -0.2794)
			(stroke
				(width 0.1)
				(type default)
			)
			(layer "F.Fab")
		)
		(fp_line
			(start -0.67945 -0.305054)
			(end -0.12065 -0.305054)
			(stroke
				(width 0.1)
				(type default)
			)
			(layer "F.Fab")
		)
		(fp_line
			(start 0.67945 -0.3048)
			(end 0.67945 0.3048)
			(stroke
				(width 0.1)
				(type default)
			)
			(layer "F.Fab")
		)
		(fp_line
			(start 0.12065 -0.3048)
			(end 0.67945 -0.3048)
			(stroke
				(width 0.1)
				(type default)
			)
			(layer "F.Fab")
		)
		(fp_line
			(start 0.12065 -0.2794)
			(end 0.12065 -0.3048)
			(stroke
				(width 0.1)
				(type default)
			)
			(layer "F.Fab")
		)
		(fp_line
			(start -0.12065 -0.2794)
			(end 0.12065 -0.2794)
			(stroke
				(width 0.1)
				(type default)
			)
			(layer "F.Fab")
		)
		(fp_line
			(start 0.120396 0.2794)
			(end -0.12065 0.2794)
			(stroke
				(width 0.1)
				(type default)
			)
			(layer "F.Fab")
		)
		(fp_line
			(start -0.12065 0.2794)
			(end -0.12065 0.3048)
			(stroke
				(width 0.1)
				(type default)
			)
			(layer "F.Fab")
		)
		(fp_line
			(start 0.67945 0.3048)
			(end 0.120396 0.3048)
			(stroke
				(width 0.1)
				(type default)
			)
			(layer "F.Fab")
		)
		(fp_line
			(start 0.120396 0.3048)
			(end 0.120396 0.2794)
			(stroke
				(width 0.1)
				(type default)
			)
			(layer "F.Fab")
		)
		(fp_line
			(start -0.12065 0.3048)
			(end -0.67945 0.3048)
			(stroke
				(width 0.1)
				(type default)
			)
			(layer "F.Fab")
		)
		(fp_line
			(start -0.67945 0.3048)
			(end -0.67945 -0.305054)
			(stroke
				(width 0.1)
				(type default)
			)
			(layer "F.Fab")
		)
		(pad "1" smd circle
			(at -0.40005 0 90)
			(size 0 0)
			(layers "F.Cu" "F.Mask" "F.Paste")
			(net "GND")
		)
		(pad "2" smd circle
			(at 0.40005 0 90)
			(size 0 0)
			(layers "F.Cu" "F.Mask" "F.Paste")
			(net "P1V8_PEX")
		)
	)
	(footprint ""
		(layer "F.Cu")
		(at 83.650074 -50.96383 180)
		(property "Reference" "PC539"
			(at 0 0 180)
			(layer "F.SilkS")
			(hide yes)
			(effects
				(font
					(size 1.27 1.27)
				)
			)
		)
		(property "Value" ""
			(at 0 0 180)
			(layer "F.Fab")
			(effects
				(font
					(size 1.27 1.27)
				)
			)
		)
		(duplicate_pad_numbers_are_jumpers no)
		(fp_line
			(start 1.524 0.762)
			(end -1.524 0.762)
			(stroke
				(width 0.1524)
				(type default)
			)
			(layer "F.SilkS")
		)
		(fp_line
			(start 1.524 -0.762)
			(end 1.524 0.762)
			(stroke
				(width 0.1524)
				(type default)
			)
			(layer "F.SilkS")
		)
		(fp_line
			(start -1.524 0.762)
			(end -1.524 -0.762)
			(stroke
				(width 0.1524)
				(type default)
			)
			(layer "F.SilkS")
		)
		(fp_line
			(start -1.524 -0.762)
			(end 1.524 -0.762)
			(stroke
				(width 0.1524)
				(type default)
			)
			(layer "F.SilkS")
		)
		(fp_line
			(start 1.1049 0.724916)
			(end 1.1049 -0.724916)
			(stroke
				(width 0.1)
				(type default)
			)
			(layer "F.Fab")
		)
		(fp_line
			(start 1.1049 -0.724916)
			(end -1.1049 -0.724916)
			(stroke
				(width 0.1)
				(type default)
			)
			(layer "F.Fab")
		)
		(fp_line
			(start -1.1049 0.724916)
			(end 1.1049 0.724916)
			(stroke
				(width 0.1)
				(type default)
			)
			(layer "F.Fab")
		)
		(fp_line
			(start -1.1049 -0.724916)
			(end -1.1049 0.724916)
			(stroke
				(width 0.1)
				(type default)
			)
			(layer "F.Fab")
		)
		(pad "1" smd rect
			(at -0.889 0)
			(size 1.016 1.27)
			(layers "F.Cu" "F.Mask" "F.Paste")
			(net "P3V3_SSD3")
		)
		(pad "2" smd rect
			(at 0.889 0)
			(size 1.016 1.27)
			(layers "F.Cu" "F.Mask" "F.Paste")
			(net "GND")
		)
	)
	(footprint ""
		(layer "F.Cu")
		(at 41.142666 -70.844918 -90)
		(property "Reference" "PD87"
			(at 3.839718 2.126996 90)
			(unlocked yes)
			(layer "F.SilkS")
			(effects
				(font
					(size 0.7874 0.5842)
					(thickness 0.1524)
				)
				(justify left)
			)
		)
		(property "Value" ""
			(at 0 0 270)
			(layer "F.Fab")
			(effects
				(font
					(size 1.27 1.27)
				)
			)
		)
		(duplicate_pad_numbers_are_jumpers no)
		(fp_line
			(start -3.400044 1.459992)
			(end -3.400044 -1.459992)
			(stroke
				(width 0.1524)
				(type default)
			)
			(layer "F.SilkS")
		)
		(fp_line
			(start 4.107942 1.459992)
			(end -3.400044 1.459992)
			(stroke
				(width 0.1524)
				(type default)
			)
			(layer "F.SilkS")
		)
		(fp_line
			(start -3.400044 -1.459992)
			(end 4.107942 -1.459992)
			(stroke
				(width 0.1524)
				(type default)
			)
			(layer "F.SilkS")
		)
		(fp_line
			(start 4.107942 -1.459992)
			(end 4.107942 1.459992)
			(stroke
				(width 0.1524)
				(type default)
			)
			(layer "F.SilkS")
		)
		(fp_poly
			(pts
				(xy 4.107942 -1.459992) (xy 4.107942 1.459992) (xy 3.308096 1.459992) (xy 3.308096 -1.459992)
			)
			(stroke
				(width 0)
				(type default)
			)
			(fill yes)
			(layer "F.SilkS")
		)
		(fp_line
			(start -2.29997 1.459992)
			(end -2.29997 -1.459992)
			(stroke
				(width 0.1)
				(type default)
			)
			(layer "F.Fab")
		)
		(fp_line
			(start 2.29997 1.459992)
			(end -2.29997 1.459992)
			(stroke
				(width 0.1)
				(type default)
			)
			(layer "F.Fab")
		)
		(fp_line
			(start -2.29997 -1.459992)
			(end 2.29997 -1.459992)
			(stroke
				(width 0.1)
				(type default)
			)
			(layer "F.Fab")
		)
		(fp_line
			(start 2.29997 -1.459992)
			(end 2.29997 1.459992)
			(stroke
				(width 0.1)
				(type default)
			)
			(layer "F.Fab")
		)
		(fp_text user "-"
			(at 5.4102 0.29845 90)
			(unlocked yes)
			(layer "F.SilkS")
			(effects
				(font
					(size 1.905 1.4224)
					(thickness 0.1524)
				)
				(justify left)
			)
		)
		(fp_text user "+"
			(at -5.239258 -0.200914 270)
			(unlocked yes)
			(layer "F.SilkS")
			(effects
				(font
					(size 1.905 1.4224)
					(thickness 0.1524)
				)
				(justify left)
			)
		)
		(fp_text user "-"
			(at 5.4102 0.29845 90)
			(unlocked yes)
			(layer "F.Fab")
			(effects
				(font
					(size 1.905 1.4224)
					(thickness 0.1524)
				)
				(justify left)
			)
		)
		(fp_text user "+"
			(at -4.7752 -0.12065 270)
			(unlocked yes)
			(layer "F.Fab")
			(effects
				(font
					(size 1.905 1.4224)
					(thickness 0.1524)
				)
				(justify left)
			)
		)
		(pad "A" smd rect
			(at -1.999996 0)
			(size 1.7018 2.5146)
			(layers "F.Cu" "F.Mask" "F.Paste")
			(net "GND")
		)
		(pad "C" smd rect
			(at 1.999996 0)
			(size 1.7018 2.5146)
			(layers "F.Cu" "F.Mask" "F.Paste")
			(net "P12V_SSD1_R")
		)
	)
	(footprint ""
		(layer "F.Cu")
		(at 39.280592 -110.088934)
		(property "Reference" "C51"
			(at 0 0 0)
			(layer "F.SilkS")
			(hide yes)
			(effects
				(font
					(size 1.27 1.27)
				)
			)
		)
		(property "Value" ""
			(at 0 0 0)
			(layer "F.Fab")
			(effects
				(font
					(size 1.27 1.27)
				)
			)
		)
		(duplicate_pad_numbers_are_jumpers no)
		(fp_line
			(start -0.299974 -0.150114)
			(end 0.299974 -0.150114)
			(stroke
				(width 0.1)
				(type default)
			)
			(layer "F.Fab")
		)
		(fp_line
			(start -0.299974 0.150114)
			(end -0.299974 -0.150114)
			(stroke
				(width 0.1)
				(type default)
			)
			(layer "F.Fab")
		)
		(fp_line
			(start 0.299974 -0.150114)
			(end 0.299974 0.150114)
			(stroke
				(width 0.1)
				(type default)
			)
			(layer "F.Fab")
		)
		(fp_line
			(start 0.299974 0.150114)
			(end -0.299974 0.150114)
			(stroke
				(width 0.1)
				(type default)
			)
			(layer "F.Fab")
		)
		(pad "1" smd rect
			(at -0.2667 0)
			(size 0.3048 0.381)
			(layers "F.Cu" "F.Mask" "F.Paste")
			(net "P5E_PEX0_STN1_TX_DP<22>")
		)
		(pad "2" smd rect
			(at 0.2667 0)
			(size 0.3048 0.381)
			(layers "F.Cu" "F.Mask" "F.Paste")
			(net "P5E_PEX0_STN1_TX_C_DP<22>")
		)
	)
	(footprint ""
		(layer "F.Cu")
		(at 378.079 -214.376 90)
		(property "Reference" "C3597"
			(at 0 0 90)
			(layer "F.SilkS")
			(hide yes)
			(effects
				(font
					(size 1.27 1.27)
				)
			)
		)
		(property "Value" ""
			(at 0 0 90)
			(layer "F.Fab")
			(effects
				(font
					(size 1.27 1.27)
				)
			)
		)
		(duplicate_pad_numbers_are_jumpers no)
		(fp_line
			(start 0.7874 -0.4064)
			(end 0.7874 0.4064)
			(stroke
				(width 0.1524)
				(type default)
			)
			(layer "F.SilkS")
		)
		(fp_line
			(start -0.7874 -0.4064)
			(end 0.7874 -0.4064)
			(stroke
				(width 0.1524)
				(type default)
			)
			(layer "F.SilkS")
		)
		(fp_line
			(start 0.7874 0.4064)
			(end -0.7874 0.4064)
			(stroke
				(width 0.1524)
				(type default)
			)
			(layer "F.SilkS")
		)
		(fp_line
			(start -0.7874 0.4064)
			(end -0.7874 -0.4064)
			(stroke
				(width 0.1524)
				(type default)
			)
			(layer "F.SilkS")
		)
		(fp_line
			(start -0.12065 -0.305054)
			(end -0.12065 -0.2794)
			(stroke
				(width 0.1)
				(type default)
			)
			(layer "F.Fab")
		)
		(fp_line
			(start -0.67945 -0.305054)
			(end -0.12065 -0.305054)
			(stroke
				(width 0.1)
				(type default)
			)
			(layer "F.Fab")
		)
		(fp_line
			(start 0.67945 -0.3048)
			(end 0.67945 0.3048)
			(stroke
				(width 0.1)
				(type default)
			)
			(layer "F.Fab")
		)
		(fp_line
			(start 0.12065 -0.3048)
			(end 0.67945 -0.3048)
			(stroke
				(width 0.1)
				(type default)
			)
			(layer "F.Fab")
		)
		(fp_line
			(start 0.12065 -0.2794)
			(end 0.12065 -0.3048)
			(stroke
				(width 0.1)
				(type default)
			)
			(layer "F.Fab")
		)
		(fp_line
			(start -0.12065 -0.2794)
			(end 0.12065 -0.2794)
			(stroke
				(width 0.1)
				(type default)
			)
			(layer "F.Fab")
		)
		(fp_line
			(start 0.120396 0.2794)
			(end -0.12065 0.2794)
			(stroke
				(width 0.1)
				(type default)
			)
			(layer "F.Fab")
		)
		(fp_line
			(start -0.12065 0.2794)
			(end -0.12065 0.3048)
			(stroke
				(width 0.1)
				(type default)
			)
			(layer "F.Fab")
		)
		(fp_line
			(start 0.67945 0.3048)
			(end 0.120396 0.3048)
			(stroke
				(width 0.1)
				(type default)
			)
			(layer "F.Fab")
		)
		(fp_line
			(start 0.120396 0.3048)
			(end 0.120396 0.2794)
			(stroke
				(width 0.1)
				(type default)
			)
			(layer "F.Fab")
		)
		(fp_line
			(start -0.12065 0.3048)
			(end -0.67945 0.3048)
			(stroke
				(width 0.1)
				(type default)
			)
			(layer "F.Fab")
		)
		(fp_line
			(start -0.67945 0.3048)
			(end -0.67945 -0.305054)
			(stroke
				(width 0.1)
				(type default)
			)
			(layer "F.Fab")
		)
		(pad "1" smd circle
			(at -0.40005 0 90)
			(size 0 0)
			(layers "F.Cu" "F.Mask" "F.Paste")
			(net "P3V3_AUX")
		)
		(pad "2" smd circle
			(at 0.40005 0 90)
			(size 0 0)
			(layers "F.Cu" "F.Mask" "F.Paste")
			(net "GND")
		)
	)
)
